(kicad_pcb
	(version 20260206)
	(generator "pcbnew")
	(generator_version "10.0")
	(general
		(thickness 1.6)
		(legacy_teardrops no)
	)
	(paper "A4")
	(title_block
		(title "01162023_DA0F0TEBIF0_F0T_Expander_BD_F_brd_V02_OCP.brd")
		(comment 1 "Grand Teton / footprints 5644-5649 of 9728")
	)
	(layers
		(0 "F.Cu" signal "TOP")
		(4 "In1.Cu" signal "GND")
		(6 "In2.Cu" signal "VCC")
		(8 "In3.Cu" signal "VCC1")
		(10 "In4.Cu" signal "GND1")
		(12 "In5.Cu" signal "IN1")
		(14 "In6.Cu" signal "GND2")
		(16 "In7.Cu" signal "IN2")
		(18 "In8.Cu" signal "GND3")
		(20 "In9.Cu" signal "IN3")
		(22 "In10.Cu" signal "GND4")
		(24 "In11.Cu" signal "IN4")
		(26 "In12.Cu" signal "GND5")
		(28 "In13.Cu" signal "IN5")
		(30 "In14.Cu" signal "GND6")
		(32 "In15.Cu" signal "IN6")
		(34 "In16.Cu" signal "GND7")
		(2 "B.Cu" signal "BOTTOM")
		(9 "F.Adhes" user "F.Adhesive")
		(11 "B.Adhes" user "B.Adhesive")
		(13 "F.Paste" user "Package Geometry/Pastemask Top")
		(15 "B.Paste" user "Package Geometry/Pastemask Bottom")
		(5 "F.SilkS" user "Ref Des/Silkscreen Top")
		(7 "B.SilkS" user "Ref Des/Silkscreen Bottom")
		(1 "F.Mask" user "Board Geometry/Soldermask Top")
		(3 "B.Mask" user "Board Geometry/Soldermask Bottom")
		(17 "Dwgs.User" user "User.Drawings")
		(19 "Cmts.User" user "User.Comments")
		(21 "Eco1.User" user "User.Eco1")
		(23 "Eco2.User" user "User.Eco2")
		(25 "Edge.Cuts" user "Board Geometry/Outline")
		(27 "Margin" user)
		(31 "F.CrtYd" user "Package Geometry/Place Bound Top")
		(29 "B.CrtYd" user "Package Geometry/Place Bound Bottom")
		(35 "F.Fab" user "Ref Des/Assembly Top")
		(33 "B.Fab" user "Ref Des/Assembly Bottom")
	)
	(footprint ""
		(layer "F.Cu")
		(at 452.567802 -55.083456)
		(property "Reference" "PC589"
			(at 0 0 0)
			(layer "F.SilkS")
			(hide yes)
			(effects
				(font
					(size 1.27 1.27)
				)
			)
		)
		(property "Value" ""
			(at 0 0 0)
			(layer "F.Fab")
			(effects
				(font
					(size 1.27 1.27)
				)
			)
		)
		(duplicate_pad_numbers_are_jumpers no)
		(fp_line
			(start -0.7874 -0.4064)
			(end 0.7874 -0.4064)
			(stroke
				(width 0.1524)
				(type default)
			)
			(layer "F.SilkS")
		)
		(fp_line
			(start -0.7874 0.4064)
			(end -0.7874 -0.4064)
			(stroke
				(width 0.1524)
				(type default)
			)
			(layer "F.SilkS")
		)
		(fp_line
			(start 0.7874 -0.4064)
			(end 0.7874 0.4064)
			(stroke
				(width 0.1524)
				(type default)
			)
			(layer "F.SilkS")
		)
		(fp_line
			(start 0.7874 0.4064)
			(end -0.7874 0.4064)
			(stroke
				(width 0.1524)
				(type default)
			)
			(layer "F.SilkS")
		)
		(fp_line
			(start -0.67945 -0.305054)
			(end -0.12065 -0.305054)
			(stroke
				(width 0.1)
				(type default)
			)
			(layer "F.Fab")
		)
		(fp_line
			(start -0.67945 0.3048)
			(end -0.67945 -0.305054)
			(stroke
				(width 0.1)
				(type default)
			)
			(layer "F.Fab")
		)
		(fp_line
			(start -0.12065 -0.305054)
			(end -0.12065 -0.2794)
			(stroke
				(width 0.1)
				(type default)
			)
			(layer "F.Fab")
		)
		(fp_line
			(start -0.12065 -0.2794)
			(end 0.12065 -0.2794)
			(stroke
				(width 0.1)
				(type default)
			)
			(layer "F.Fab")
		)
		(fp_line
			(start -0.12065 0.2794)
			(end -0.12065 0.3048)
			(stroke
				(width 0.1)
				(type default)
			)
			(layer "F.Fab")
		)
		(fp_line
			(start -0.12065 0.3048)
			(end -0.67945 0.3048)
			(stroke
				(width 0.1)
				(type default)
			)
			(layer "F.Fab")
		)
		(fp_line
			(start 0.120396 0.2794)
			(end -0.12065 0.2794)
			(stroke
				(width 0.1)
				(type default)
			)
			(layer "F.Fab")
		)
		(fp_line
			(start 0.120396 0.3048)
			(end 0.120396 0.2794)
			(stroke
				(width 0.1)
				(type default)
			)
			(layer "F.Fab")
		)
		(fp_line
			(start 0.12065 -0.3048)
			(end 0.67945 -0.3048)
			(stroke
				(width 0.1)
				(type default)
			)
			(layer "F.Fab")
		)
		(fp_line
			(start 0.12065 -0.2794)
			(end 0.12065 -0.3048)
			(stroke
				(width 0.1)
				(type default)
			)
			(layer "F.Fab")
		)
		(fp_line
			(start 0.67945 -0.3048)
			(end 0.67945 0.3048)
			(stroke
				(width 0.1)
				(type default)
			)
			(layer "F.Fab")
		)
		(fp_line
			(start 0.67945 0.3048)
			(end 0.120396 0.3048)
			(stroke
				(width 0.1)
				(type default)
			)
			(layer "F.Fab")
		)
		(pad "1" smd circle
			(at -0.40005 0)
			(size 0 0)
			(layers "F.Cu" "F.Mask" "F.Paste")
			(net "P5V_AUX")
		)
		(pad "2" smd circle
			(at 0.40005 0)
			(size 0 0)
			(layers "F.Cu" "F.Mask" "F.Paste")
			(net "GND")
		)
	)
	(footprint ""
		(layer "F.Cu")
		(at 411.403292 -204.364082)
		(property "Reference" "Q237"
			(at 3.431286 -2.287016 0)
			(unlocked yes)
			(layer "F.SilkS")
			(effects
				(font
					(size 0.7874 0.5842)
					(thickness 0.1524)
				)
			)
		)
		(property "Value" ""
			(at 0 0 0)
			(layer "F.Fab")
			(effects
				(font
					(size 1.27 1.27)
				)
			)
		)
		(duplicate_pad_numbers_are_jumpers no)
		(fp_line
			(start -1.376172 -1.199896)
			(end -0.508 -1.199896)
			(stroke
				(width 0.1524)
				(type default)
			)
			(layer "F.SilkS")
		)
		(fp_line
			(start -1.376172 1.199896)
			(end -1.376172 -1.199896)
			(stroke
				(width 0.1524)
				(type default)
			)
			(layer "F.SilkS")
		)
		(fp_line
			(start -0.508 -1.199896)
			(end 0 -0.762)
			(stroke
				(width 0.1524)
				(type default)
			)
			(layer "F.SilkS")
		)
		(fp_line
			(start 0 -0.762)
			(end 0.508 -1.199896)
			(stroke
				(width 0.1524)
				(type default)
			)
			(layer "F.SilkS")
		)
		(fp_line
			(start 0.508 -1.199896)
			(end 1.376172 -1.199896)
			(stroke
				(width 0.1524)
				(type default)
			)
			(layer "F.SilkS")
		)
		(fp_line
			(start 1.376172 -1.199896)
			(end 1.376172 1.199896)
			(stroke
				(width 0.1524)
				(type default)
			)
			(layer "F.SilkS")
		)
		(fp_line
			(start 1.376172 1.199896)
			(end -1.376172 1.199896)
			(stroke
				(width 0.1524)
				(type default)
			)
			(layer "F.SilkS")
		)
		(fp_poly
			(pts
				(xy -1.4605 -0.7493) (xy -2.2225 -1.1303) (xy -2.2225 -0.3683)
			)
			(stroke
				(width 0)
				(type default)
			)
			(fill yes)
			(layer "F.SilkS")
		)
		(fp_line
			(start -0.674878 -1.100074)
			(end 0.674878 -1.100074)
			(stroke
				(width 0.1)
				(type default)
			)
			(layer "F.Fab")
		)
		(fp_line
			(start -0.674878 1.100074)
			(end -0.674878 -1.100074)
			(stroke
				(width 0.1)
				(type default)
			)
			(layer "F.Fab")
		)
		(fp_line
			(start 0.674878 -1.100074)
			(end 0.674878 1.100074)
			(stroke
				(width 0.1)
				(type default)
			)
			(layer "F.Fab")
		)
		(fp_line
			(start 0.674878 1.100074)
			(end -0.674878 1.100074)
			(stroke
				(width 0.1)
				(type default)
			)
			(layer "F.Fab")
		)
		(fp_poly
			(pts
				(xy -1.4605 -0.7493) (xy -2.2225 -1.1303) (xy -2.2225 -0.3683)
			)
			(stroke
				(width 0)
				(type default)
			)
			(fill yes)
			(layer "F.Fab")
		)
		(pad "1" smd rect
			(at -0.899922 -0.750062 270)
			(size 0.6096 0.6096)
			(layers "F.Cu" "F.Mask" "F.Paste")
			(net "GND")
		)
		(pad "2" smd rect
			(at -0.899922 0 270)
			(size 0.4064 0.6096)
			(layers "F.Cu" "F.Mask" "F.Paste")
			(net "FPGA_PEX2_MODE_SEL2_R")
		)
		(pad "3" smd rect
			(at -0.899922 0.750062 270)
			(size 0.6096 0.6096)
			(layers "F.Cu" "F.Mask" "F.Paste")
			(net "FPGA_PEX2_MODE_SEL2_ISO")
		)
		(pad "4" smd rect
			(at 0.899922 0.750062 270)
			(size 0.6096 0.6096)
			(layers "F.Cu" "F.Mask" "F.Paste")
			(net "GND")
		)
		(pad "5" smd rect
			(at 0.899922 0 270)
			(size 0.4064 0.6096)
			(layers "F.Cu" "F.Mask" "F.Paste")
			(net "FPGA_PEX2_MODE_SEL2_D_N")
		)
		(pad "6" smd rect
			(at 0.899922 -0.750062 270)
			(size 0.6096 0.6096)
			(layers "F.Cu" "F.Mask" "F.Paste")
			(net "FPGA_PEX2_MODE_SEL2_D_N")
		)
	)
	(footprint ""
		(layer "F.Cu")
		(at 148.511514 -293.245032 -90)
		(property "Reference" "R4570"
			(at 0 0 270)
			(layer "F.SilkS")
			(hide yes)
			(effects
				(font
					(size 1.27 1.27)
				)
			)
		)
		(property "Value" ""
			(at 0 0 270)
			(layer "F.Fab")
			(effects
				(font
					(size 1.27 1.27)
				)
			)
		)
		(duplicate_pad_numbers_are_jumpers no)
		(fp_line
			(start -0.7874 0.4064)
			(end -0.7874 -0.4064)
			(stroke
				(width 0.1524)
				(type default)
			)
			(layer "F.SilkS")
		)
		(fp_line
			(start 0.7874 0.4064)
			(end -0.7874 0.4064)
			(stroke
				(width 0.1524)
				(type default)
			)
			(layer "F.SilkS")
		)
		(fp_line
			(start -0.7874 -0.4064)
			(end 0.7874 -0.4064)
			(stroke
				(width 0.1524)
				(type default)
			)
			(layer "F.SilkS")
		)
		(fp_line
			(start 0.7874 -0.4064)
			(end 0.7874 0.4064)
			(stroke
				(width 0.1524)
				(type default)
			)
			(layer "F.SilkS")
		)
		(fp_line
			(start -0.67945 0.3048)
			(end -0.67945 -0.305054)
			(stroke
				(width 0.1)
				(type default)
			)
			(layer "F.Fab")
		)
		(fp_line
			(start -0.12065 0.3048)
			(end -0.67945 0.3048)
			(stroke
				(width 0.1)
				(type default)
			)
			(layer "F.Fab")
		)
		(fp_line
			(start 0.120396 0.3048)
			(end 0.120396 0.2794)
			(stroke
				(width 0.1)
				(type default)
			)
			(layer "F.Fab")
		)
		(fp_line
			(start 0.67945 0.3048)
			(end 0.120396 0.3048)
			(stroke
				(width 0.1)
				(type default)
			)
			(layer "F.Fab")
		)
		(fp_line
			(start -0.12065 0.2794)
			(end -0.12065 0.3048)
			(stroke
				(width 0.1)
				(type default)
			)
			(layer "F.Fab")
		)
		(fp_line
			(start 0.120396 0.2794)
			(end -0.12065 0.2794)
			(stroke
				(width 0.1)
				(type default)
			)
			(layer "F.Fab")
		)
		(fp_line
			(start -0.12065 -0.2794)
			(end 0.12065 -0.2794)
			(stroke
				(width 0.1)
				(type default)
			)
			(layer "F.Fab")
		)
		(fp_line
			(start 0.12065 -0.2794)
			(end 0.12065 -0.3048)
			(stroke
				(width 0.1)
				(type default)
			)
			(layer "F.Fab")
		)
		(fp_line
			(start 0.12065 -0.3048)
			(end 0.67945 -0.3048)
			(stroke
				(width 0.1)
				(type default)
			)
			(layer "F.Fab")
		)
		(fp_line
			(start 0.67945 -0.3048)
			(end 0.67945 0.3048)
			(stroke
				(width 0.1)
				(type default)
			)
			(layer "F.Fab")
		)
		(fp_line
			(start -0.67945 -0.305054)
			(end -0.12065 -0.305054)
			(stroke
				(width 0.1)
				(type default)
			)
			(layer "F.Fab")
		)
		(fp_line
			(start -0.12065 -0.305054)
			(end -0.12065 -0.2794)
			(stroke
				(width 0.1)
				(type default)
			)
			(layer "F.Fab")
		)
		(pad "1" smd circle
			(at -0.40005 0 270)
			(size 0 0)
			(layers "F.Cu" "F.Mask" "F.Paste")
			(net "PCEPLL2_VDDA18_PEX1")
		)
		(pad "2" smd circle
			(at 0.40005 0 270)
			(size 0 0)
			(layers "F.Cu" "F.Mask" "F.Paste")
			(net "PCEPLL2_VDDA18_PEX1_R")
		)
	)
	(footprint ""
		(layer "F.Cu")
		(at 146.94789 -40.037258 90)
		(property "Reference" "U368"
			(at 0.247142 2.40538 90)
			(unlocked yes)
			(layer "F.SilkS")
			(effects
				(font
					(size 0.7874 0.5842)
					(thickness 0.1524)
				)
			)
		)
		(property "Value" ""
			(at 0 0 90)
			(layer "F.Fab")
			(effects
				(font
					(size 1.27 1.27)
				)
			)
		)
		(duplicate_pad_numbers_are_jumpers no)
		(fp_line
			(start -1.949958 -1.610106)
			(end 1.949958 -1.610106)
			(stroke
				(width 0.1524)
				(type default)
			)
			(layer "F.SilkS")
		)
		(fp_line
			(start 1.949958 -1.560068)
			(end 1.949958 1.610106)
			(stroke
				(width 0.1524)
				(type default)
			)
			(layer "F.SilkS")
		)
		(fp_line
			(start 1.949958 1.610106)
			(end -1.949958 1.610106)
			(stroke
				(width 0.1524)
				(type default)
			)
			(layer "F.SilkS")
		)
		(fp_line
			(start -1.949958 1.610106)
			(end -1.949958 -1.610106)
			(stroke
				(width 0.1524)
				(type default)
			)
			(layer "F.SilkS")
		)
		(fp_line
			(start 0.750062 -1.560068)
			(end 0.750062 1.560068)
			(stroke
				(width 0.1)
				(type default)
			)
			(layer "F.Fab")
		)
		(fp_line
			(start -0.750062 -1.560068)
			(end 0.750062 -1.560068)
			(stroke
				(width 0.1)
				(type default)
			)
			(layer "F.Fab")
		)
		(fp_line
			(start 0.750062 1.560068)
			(end -0.750062 1.560068)
			(stroke
				(width 0.1)
				(type default)
			)
			(layer "F.Fab")
		)
		(fp_line
			(start -0.750062 1.560068)
			(end -0.750062 -1.560068)
			(stroke
				(width 0.1)
				(type default)
			)
			(layer "F.Fab")
		)
		(pad "D" smd rect
			(at 1.100074 0)
			(size 1.016 1.4224)
			(layers "F.Cu" "F.Mask" "F.Paste")
			(net "SSD5_AUX_P3V3_EN")
		)
		(pad "G" smd rect
			(at -1.100074 -0.94996)
			(size 1.016 1.4224)
			(layers "F.Cu" "F.Mask" "F.Paste")
			(net "PRSNT_SSD5_R1_N")
		)
		(pad "S" smd rect
			(at -1.100074 0.94996)
			(size 1.016 1.4224)
			(layers "F.Cu" "F.Mask" "F.Paste")
			(net "GND")
		)
	)
	(footprint ""
		(layer "F.Cu")
		(at 345.057476 -313.620404)
		(property "Reference" "L62"
			(at 0 0 0)
			(layer "F.SilkS")
			(hide yes)
			(effects
				(font
					(size 1.27 1.27)
				)
			)
		)
		(property "Value" ""
			(at 0 0 0)
			(layer "F.Fab")
			(effects
				(font
					(size 1.27 1.27)
				)
			)
		)
		(duplicate_pad_numbers_are_jumpers no)
		(fp_line
			(start -2.248154 -4.9911)
			(end -2.248154 -1.677416)
			(stroke
				(width 0.1524)
				(type default)
			)
			(layer "F.SilkS")
		)
		(fp_line
			(start -2.248154 1.660398)
			(end -2.248154 4.9911)
			(stroke
				(width 0.1524)
				(type default)
			)
			(layer "F.SilkS")
		)
		(fp_line
			(start -2.248154 4.9911)
			(end 2.248154 4.9911)
			(stroke
				(width 0.1524)
				(type default)
			)
			(layer "F.SilkS")
		)
		(fp_line
			(start 2.248154 -4.9911)
			(end -2.248154 -4.9911)
			(stroke
				(width 0.1524)
				(type default)
			)
			(layer "F.SilkS")
		)
		(fp_line
			(start 2.248154 -1.787144)
			(end 2.248154 -4.9911)
			(stroke
				(width 0.1524)
				(type default)
			)
			(layer "F.SilkS")
		)
		(fp_line
			(start 2.248154 4.9911)
			(end 2.248154 1.70434)
			(stroke
				(width 0.1524)
				(type default)
			)
			(layer "F.SilkS")
		)
		(fp_line
			(start -1.700022 -0.899922)
			(end -1.700022 0.899922)
			(stroke
				(width 0.1)
				(type default)
			)
			(layer "F.Fab")
		)
		(fp_line
			(start -1.700022 0.899922)
			(end 1.700022 0.899922)
			(stroke
				(width 0.1)
				(type default)
			)
			(layer "F.Fab")
		)
		(fp_line
			(start 1.700022 -0.899922)
			(end -1.700022 -0.899922)
			(stroke
				(width 0.1)
				(type default)
			)
			(layer "F.Fab")
		)
		(fp_line
			(start 1.700022 0.899922)
			(end 1.700022 -0.899922)
			(stroke
				(width 0.1)
				(type default)
			)
			(layer "F.Fab")
		)
		(pad "1" smd rect
			(at -1.575054 0)
			(size 1.1684 9.8044)
			(layers "F.Cu" "F.Mask" "F.Paste")
			(net "P0V8_PEX2")
		)
		(pad "2" smd rect
			(at 1.575054 0)
			(size 1.1684 9.8044)
			(layers "F.Cu" "F.Mask" "F.Paste")
			(net "P0V8_SERDES_VDDA_PEX2")
		)
	)
	(footprint ""
		(layer "F.Cu")
		(at 96.4692 -196.4944 90)
		(property "Reference" "C4444"
			(at 0 0 90)
			(layer "F.SilkS")
			(hide yes)
			(effects
				(font
					(size 1.27 1.27)
				)
			)
		)
		(property "Value" ""
			(at 0 0 90)
			(layer "F.Fab")
			(effects
				(font
					(size 1.27 1.27)
				)
			)
		)
		(duplicate_pad_numbers_are_jumpers no)
		(fp_line
			(start 0.7874 -0.4064)
			(end 0.7874 0.4064)
			(stroke
				(width 0.1524)
				(type default)
			)
			(layer "F.SilkS")
		)
		(fp_line
			(start -0.7874 -0.4064)
			(end 0.7874 -0.4064)
			(stroke
				(width 0.1524)
				(type default)
			)
			(layer "F.SilkS")
		)
		(fp_line
			(start 0.7874 0.4064)
			(end -0.7874 0.4064)
			(stroke
				(width 0.1524)
				(type default)
			)
			(layer "F.SilkS")
		)
		(fp_line
			(start -0.7874 0.4064)
			(end -0.7874 -0.4064)
			(stroke
				(width 0.1524)
				(type default)
			)
			(layer "F.SilkS")
		)
		(fp_line
			(start -0.12065 -0.305054)
			(end -0.12065 -0.2794)
			(stroke
				(width 0.1)
				(type default)
			)
			(layer "F.Fab")
		)
		(fp_line
			(start -0.67945 -0.305054)
			(end -0.12065 -0.305054)
			(stroke
				(width 0.1)
				(type default)
			)
			(layer "F.Fab")
		)
		(fp_line
			(start 0.67945 -0.3048)
			(end 0.67945 0.3048)
			(stroke
				(width 0.1)
				(type default)
			)
			(layer "F.Fab")
		)
		(fp_line
			(start 0.12065 -0.3048)
			(end 0.67945 -0.3048)
			(stroke
				(width 0.1)
				(type default)
			)
			(layer "F.Fab")
		)
		(fp_line
			(start 0.12065 -0.2794)
			(end 0.12065 -0.3048)
			(stroke
				(width 0.1)
				(type default)
			)
			(layer "F.Fab")
		)
		(fp_line
			(start -0.12065 -0.2794)
			(end 0.12065 -0.2794)
			(stroke
				(width 0.1)
				(type default)
			)
			(layer "F.Fab")
		)
		(fp_line
			(start 0.120396 0.2794)
			(end -0.12065 0.2794)
			(stroke
				(width 0.1)
				(type default)
			)
			(layer "F.Fab")
		)
		(fp_line
			(start -0.12065 0.2794)
			(end -0.12065 0.3048)
			(stroke
				(width 0.1)
				(type default)
			)
			(layer "F.Fab")
		)
		(fp_line
			(start 0.67945 0.3048)
			(end 0.120396 0.3048)
			(stroke
				(width 0.1)
				(type default)
			)
			(layer "F.Fab")
		)
		(fp_line
			(start 0.120396 0.3048)
			(end 0.120396 0.2794)
			(stroke
				(width 0.1)
				(type default)
			)
			(layer "F.Fab")
		)
		(fp_line
			(start -0.12065 0.3048)
			(end -0.67945 0.3048)
			(stroke
				(width 0.1)
				(type default)
			)
			(layer "F.Fab")
		)
		(fp_line
			(start -0.67945 0.3048)
			(end -0.67945 -0.305054)
			(stroke
				(width 0.1)
				(type default)
			)
			(layer "F.Fab")
		)
		(pad "1" smd circle
			(at -0.40005 0 90)
			(size 0 0)
			(layers "F.Cu" "F.Mask" "F.Paste")
			(net "P3V3_AUX")
		)
		(pad "2" smd circle
			(at 0.40005 0 90)
			(size 0 0)
			(layers "F.Cu" "F.Mask" "F.Paste")
			(net "GND")
		)
	)
)
